# SCM (Grand Teton) — schematic netlist excerpt (pin names and nets, part order shuffled) for the footprints in the layout excerpt that follows; sources: Cadence DE-HDL packaged netlist, KiCad conversion of 12092022_DA0F0TMDCD0_F0T_Management_Board_D_brd_V3_OCP.brd

R332  Q_RES  120 1% CHIP  pkg 0402LF  page 20 : A = GND ; B = M_BMC_DDR4_MA<6>
R732  Q_RES  0 5% CHIP  pkg 0402LF  page 29 : A = SMB_DEBUG_AUX_LVC3_USB_SCL ; B = SMB_DEBUG_AUX_LVC3_USB_R2_SCL

(kicad_pcb
	(version 20260206)
	(generator "pcbnew")
	(generator_version "10.0")
	(general
		(thickness 1.6)
		(legacy_teardrops no)
	)
	(paper "A4")
	(title_block
		(title "12092022_DA0F0TMDCD0_F0T_Management_Board_D_brd_V3_OCP.brd")
		(comment 1 "Grand Teton / footprints 1099-1100 of 1440")
	)
	(layers
		(0 "F.Cu" signal "TOP")
		(4 "In1.Cu" signal "GND")
		(6 "In2.Cu" signal "IN1")
		(8 "In3.Cu" signal "GND1")
		(10 "In4.Cu" signal "IN2")
		(12 "In5.Cu" signal "VCC")
		(14 "In6.Cu" signal "VCC1")
		(16 "In7.Cu" signal "IN3")
		(18 "In8.Cu" signal "GND2")
		(20 "In9.Cu" signal "IN4")
		(22 "In10.Cu" signal "GND3")
		(2 "B.Cu" signal "BOTTOM")
		(9 "F.Adhes" user "F.Adhesive")
		(11 "B.Adhes" user "B.Adhesive")
		(13 "F.Paste" user "Package Geometry/Pastemask Top")
		(15 "B.Paste" user "Package Geometry/Pastemask Bottom")
		(5 "F.SilkS" user "Ref Des/Silkscreen Top")
		(7 "B.SilkS" user "Ref Des/Silkscreen Bottom")
		(1 "F.Mask" user "Board Geometry/Soldermask Top")
		(3 "B.Mask" user "Board Geometry/Soldermask Bottom")
		(17 "Dwgs.User" user "User.Drawings")
		(19 "Cmts.User" user "User.Comments")
		(21 "Eco1.User" user "User.Eco1")
		(23 "Eco2.User" user "User.Eco2")
		(25 "Edge.Cuts" user "Board Geometry/Outline")
		(27 "Margin" user)
		(31 "F.CrtYd" user "Package Geometry/Place Bound Top")
		(29 "B.CrtYd" user "Package Geometry/Place Bound Bottom")
		(35 "F.Fab" user "Ref Des/Assembly Top")
		(33 "B.Fab" user "Ref Des/Assembly Bottom")
	)
	(footprint ""
		(layer "B.Cu")
		(at 77.707744 -35.540188 -90)
		(property "Reference" "R332"
			(at 0 0 90)
			(layer "B.SilkS")
			(hide yes)
			(effects
				(font
					(size 1.27 1.27)
				)
				(justify mirror)
			)
		)
		(property "Value" ""
			(at 0 0 90)
			(layer "B.Fab")
			(effects
				(font
					(size 1.27 1.27)
				)
				(justify mirror)
			)
		)
		(duplicate_pad_numbers_are_jumpers no)
		(fp_line
			(start -0.7874 0.4064)
			(end 0.7874 0.4064)
			(stroke
				(width 0.1524)
				(type default)
			)
			(layer "B.SilkS")
		)
		(fp_line
			(start 0.7874 0.4064)
			(end 0.7874 -0.4064)
			(stroke
				(width 0.1524)
				(type default)
			)
			(layer "B.SilkS")
		)
		(fp_line
			(start -0.7874 -0.4064)
			(end -0.7874 0.4064)
			(stroke
				(width 0.1524)
				(type default)
			)
			(layer "B.SilkS")
		)
		(fp_line
			(start 0.7874 -0.4064)
			(end -0.7874 -0.4064)
			(stroke
				(width 0.1524)
				(type default)
			)
			(layer "B.SilkS")
		)
		(fp_line
			(start -0.67945 0.3048)
			(end -0.120396 0.3048)
			(stroke
				(width 0.1)
				(type default)
			)
			(layer "B.Fab")
		)
		(fp_line
			(start -0.120396 0.3048)
			(end -0.120396 0.2794)
			(stroke
				(width 0.1)
				(type default)
			)
			(layer "B.Fab")
		)
		(fp_line
			(start 0.12065 0.3048)
			(end 0.67945 0.3048)
			(stroke
				(width 0.1)
				(type default)
			)
			(layer "B.Fab")
		)
		(fp_line
			(start 0.67945 0.3048)
			(end 0.67945 -0.305054)
			(stroke
				(width 0.1)
				(type default)
			)
			(layer "B.Fab")
		)
		(fp_line
			(start -0.120396 0.2794)
			(end 0.12065 0.2794)
			(stroke
				(width 0.1)
				(type default)
			)
			(layer "B.Fab")
		)
		(fp_line
			(start 0.12065 0.2794)
			(end 0.12065 0.3048)
			(stroke
				(width 0.1)
				(type default)
			)
			(layer "B.Fab")
		)
		(fp_line
			(start -0.12065 -0.2794)
			(end -0.12065 -0.3048)
			(stroke
				(width 0.1)
				(type default)
			)
			(layer "B.Fab")
		)
		(fp_line
			(start 0.12065 -0.2794)
			(end -0.12065 -0.2794)
			(stroke
				(width 0.1)
				(type default)
			)
			(layer "B.Fab")
		)
		(fp_line
			(start -0.67945 -0.3048)
			(end -0.67945 0.3048)
			(stroke
				(width 0.1)
				(type default)
			)
			(layer "B.Fab")
		)
		(fp_line
			(start -0.12065 -0.3048)
			(end -0.67945 -0.3048)
			(stroke
				(width 0.1)
				(type default)
			)
			(layer "B.Fab")
		)
		(fp_line
			(start 0.12065 -0.305054)
			(end 0.12065 -0.2794)
			(stroke
				(width 0.1)
				(type default)
			)
			(layer "B.Fab")
		)
		(fp_line
			(start 0.67945 -0.305054)
			(end 0.12065 -0.305054)
			(stroke
				(width 0.1)
				(type default)
			)
			(layer "B.Fab")
		)
		(pad "1" smd circle
			(at 0.40005 0 90)
			(size 0 0)
			(layers "B.Cu" "B.Mask" "B.Paste")
			(net "GND")
		)
		(pad "2" smd circle
			(at -0.40005 0 90)
			(size 0 0)
			(layers "B.Cu" "B.Mask" "B.Paste")
			(net "M_BMC_DDR4_MA<6>")
		)
	)
	(footprint ""
		(layer "B.Cu")
		(at 36.77412 -96.20504 180)
		(property "Reference" "R732"
			(at 0 0 0)
			(layer "B.SilkS")
			(hide yes)
			(effects
				(font
					(size 1.27 1.27)
				)
				(justify mirror)
			)
		)
		(property "Value" ""
			(at 0 0 0)
			(layer "B.Fab")
			(effects
				(font
					(size 1.27 1.27)
				)
				(justify mirror)
			)
		)
		(duplicate_pad_numbers_are_jumpers no)
		(fp_line
			(start 0.7874 0.4064)
			(end 0.7874 -0.4064)
			(stroke
				(width 0.1524)
				(type default)
			)
			(layer "B.SilkS")
		)
		(fp_line
			(start 0.7874 -0.4064)
			(end -0.7874 -0.4064)
			(stroke
				(width 0.1524)
				(type default)
			)
			(layer "B.SilkS")
		)
		(fp_line
			(start -0.7874 0.4064)
			(end 0.7874 0.4064)
			(stroke
				(width 0.1524)
				(type default)
			)
			(layer "B.SilkS")
		)
		(fp_line
			(start -0.7874 -0.4064)
			(end -0.7874 0.4064)
			(stroke
				(width 0.1524)
				(type default)
			)
			(layer "B.SilkS")
		)
		(fp_line
			(start 0.67945 0.3048)
			(end 0.67945 -0.305054)
			(stroke
				(width 0.1)
				(type default)
			)
			(layer "B.Fab")
		)
		(fp_line
			(start 0.67945 -0.305054)
			(end 0.12065 -0.305054)
			(stroke
				(width 0.1)
				(type default)
			)
			(layer "B.Fab")
		)
		(fp_line
			(start 0.12065 0.3048)
			(end 0.67945 0.3048)
			(stroke
				(width 0.1)
				(type default)
			)
			(layer "B.Fab")
		)
		(fp_line
			(start 0.12065 0.2794)
			(end 0.12065 0.3048)
			(stroke
				(width 0.1)
				(type default)
			)
			(layer "B.Fab")
		)
		(fp_line
			(start 0.12065 -0.2794)
			(end -0.12065 -0.2794)
			(stroke
				(width 0.1)
				(type default)
			)
			(layer "B.Fab")
		)
		(fp_line
			(start 0.12065 -0.305054)
			(end 0.12065 -0.2794)
			(stroke
				(width 0.1)
				(type default)
			)
			(layer "B.Fab")
		)
		(fp_line
			(start -0.120396 0.3048)
			(end -0.120396 0.2794)
			(stroke
				(width 0.1)
				(type default)
			)
			(layer "B.Fab")
		)
		(fp_line
			(start -0.120396 0.2794)
			(end 0.12065 0.2794)
			(stroke
				(width 0.1)
				(type default)
			)
			(layer "B.Fab")
		)
		(fp_line
			(start -0.12065 -0.2794)
			(end -0.12065 -0.3048)
			(stroke
				(width 0.1)
				(type default)
			)
			(layer "B.Fab")
		)
		(fp_line
			(start -0.12065 -0.3048)
			(end -0.67945 -0.3048)
			(stroke
				(width 0.1)
				(type default)
			)
			(layer "B.Fab")
		)
		(fp_line
			(start -0.67945 0.3048)
			(end -0.120396 0.3048)
			(stroke
				(width 0.1)
				(type default)
			)
			(layer "B.Fab")
		)
		(fp_line
			(start -0.67945 -0.3048)
			(end -0.67945 0.3048)
			(stroke
				(width 0.1)
				(type default)
			)
			(layer "B.Fab")
		)
		(pad "1" smd circle
			(at 0.40005 0)
			(size 0 0)
			(layers "B.Cu" "B.Mask" "B.Paste")
			(net "SMB_DEBUG_AUX_LVC3_USB_SCL")
		)
		(pad "2" smd circle
			(at -0.40005 0)
			(size 0 0)
			(layers "B.Cu" "B.Mask" "B.Paste")
			(net "SMB_DEBUG_AUX_LVC3_USB_R2_SCL")
		)
	)
)
